(kicad_pcb
	(version 20260206)
	(generator "pcbnew")
	(generator_version "10.0")
	(general
		(thickness 1.6)
		(legacy_teardrops no)
	)
	(paper "A4")
	(title_block
		(title "03242023_DA0F0TMBIJ0_F0T_Motherboard_J_brd_V01_OCP.brd")
		(comment 1 "Grand Teton / footprints 1440-1446 of 6105")
	)
	(layers
		(0 "F.Cu" signal "TOP")
		(4 "In1.Cu" signal "GND")
		(6 "In2.Cu" signal "IN1")
		(8 "In3.Cu" signal "GND1")
		(10 "In4.Cu" signal "IN2")
		(12 "In5.Cu" signal "GND2")
		(14 "In6.Cu" signal "IN3")
		(16 "In7.Cu" signal "GND3")
		(18 "In8.Cu" signal "VCC")
		(20 "In9.Cu" signal "VCC1")
		(22 "In10.Cu" signal "GND4")
		(24 "In11.Cu" signal "IN4")
		(26 "In12.Cu" signal "GND5")
		(28 "In13.Cu" signal "IN5")
		(30 "In14.Cu" signal "GND6")
		(32 "In15.Cu" signal "IN6")
		(34 "In16.Cu" signal "GND7")
		(2 "B.Cu" signal "BOTTOM")
		(9 "F.Adhes" user "F.Adhesive")
		(11 "B.Adhes" user "B.Adhesive")
		(13 "F.Paste" user "Package Geometry/Pastemask Top")
		(15 "B.Paste" user "Package Geometry/Pastemask Bottom")
		(5 "F.SilkS" user "Ref Des/Silkscreen Top")
		(7 "B.SilkS" user "Ref Des/Silkscreen Bottom")
		(1 "F.Mask" user "Board Geometry/Soldermask Top")
		(3 "B.Mask" user "Board Geometry/Soldermask Bottom")
		(17 "Dwgs.User" user "User.Drawings")
		(19 "Cmts.User" user "User.Comments")
		(21 "Eco1.User" user "User.Eco1")
		(23 "Eco2.User" user "User.Eco2")
		(25 "Edge.Cuts" user "Board Geometry/Outline")
		(27 "Margin" user)
		(31 "F.CrtYd" user "Package Geometry/Place Bound Top")
		(29 "B.CrtYd" user "Package Geometry/Place Bound Bottom")
		(35 "F.Fab" user "Ref Des/Assembly Top")
		(33 "B.Fab" user "Ref Des/Assembly Bottom")
	)
	(footprint ""
		(layer "F.Cu")
		(at 145.981674 -408.517344 -90)
		(property "Reference" "C1532"
			(at 0 0 270)
			(layer "F.SilkS")
			(hide yes)
			(effects
				(font
					(size 1.27 1.27)
				)
			)
		)
		(property "Value" ""
			(at 0 0 270)
			(layer "F.Fab")
			(effects
				(font
					(size 1.27 1.27)
				)
			)
		)
		(duplicate_pad_numbers_are_jumpers no)
		(fp_line
			(start -0.299974 0.150114)
			(end -0.299974 -0.150114)
			(stroke
				(width 0.1)
				(type default)
			)
			(layer "F.Fab")
		)
		(fp_line
			(start 0.299974 0.150114)
			(end -0.299974 0.150114)
			(stroke
				(width 0.1)
				(type default)
			)
			(layer "F.Fab")
		)
		(fp_line
			(start -0.299974 -0.150114)
			(end 0.299974 -0.150114)
			(stroke
				(width 0.1)
				(type default)
			)
			(layer "F.Fab")
		)
		(fp_line
			(start 0.299974 -0.150114)
			(end 0.299974 0.150114)
			(stroke
				(width 0.1)
				(type default)
			)
			(layer "F.Fab")
		)
		(pad "1" smd rect
			(at -0.2667 0 270)
			(size 0.3048 0.381)
			(layers "F.Cu" "F.Mask" "F.Paste")
			(net "P5E_CPU1_PE3_TX_C_DN<7>")
		)
		(pad "2" smd rect
			(at 0.2667 0 270)
			(size 0.3048 0.381)
			(layers "F.Cu" "F.Mask" "F.Paste")
			(net "P5E_CPU1_PE3_TX_DN<7>")
		)
	)
	(footprint ""
		(layer "F.Cu")
		(at 435.157118 -44.44238)
		(property "Reference" "R2134"
			(at 0 0 0)
			(layer "F.SilkS")
			(hide yes)
			(effects
				(font
					(size 1.27 1.27)
				)
			)
		)
		(property "Value" ""
			(at 0 0 0)
			(layer "F.Fab")
			(effects
				(font
					(size 1.27 1.27)
				)
			)
		)
		(duplicate_pad_numbers_are_jumpers no)
		(fp_line
			(start -0.7874 -0.4064)
			(end 0.7874 -0.4064)
			(stroke
				(width 0.1524)
				(type default)
			)
			(layer "F.SilkS")
		)
		(fp_line
			(start -0.7874 0.4064)
			(end -0.7874 -0.4064)
			(stroke
				(width 0.1524)
				(type default)
			)
			(layer "F.SilkS")
		)
		(fp_line
			(start 0.7874 -0.4064)
			(end 0.7874 0.4064)
			(stroke
				(width 0.1524)
				(type default)
			)
			(layer "F.SilkS")
		)
		(fp_line
			(start 0.7874 0.4064)
			(end -0.7874 0.4064)
			(stroke
				(width 0.1524)
				(type default)
			)
			(layer "F.SilkS")
		)
		(fp_line
			(start -0.67945 -0.305054)
			(end -0.12065 -0.305054)
			(stroke
				(width 0.1)
				(type default)
			)
			(layer "F.Fab")
		)
		(fp_line
			(start -0.67945 0.3048)
			(end -0.67945 -0.305054)
			(stroke
				(width 0.1)
				(type default)
			)
			(layer "F.Fab")
		)
		(fp_line
			(start -0.12065 -0.305054)
			(end -0.12065 -0.2794)
			(stroke
				(width 0.1)
				(type default)
			)
			(layer "F.Fab")
		)
		(fp_line
			(start -0.12065 -0.2794)
			(end 0.12065 -0.2794)
			(stroke
				(width 0.1)
				(type default)
			)
			(layer "F.Fab")
		)
		(fp_line
			(start -0.12065 0.2794)
			(end -0.12065 0.3048)
			(stroke
				(width 0.1)
				(type default)
			)
			(layer "F.Fab")
		)
		(fp_line
			(start -0.12065 0.3048)
			(end -0.67945 0.3048)
			(stroke
				(width 0.1)
				(type default)
			)
			(layer "F.Fab")
		)
		(fp_line
			(start 0.120396 0.2794)
			(end -0.12065 0.2794)
			(stroke
				(width 0.1)
				(type default)
			)
			(layer "F.Fab")
		)
		(fp_line
			(start 0.120396 0.3048)
			(end 0.120396 0.2794)
			(stroke
				(width 0.1)
				(type default)
			)
			(layer "F.Fab")
		)
		(fp_line
			(start 0.12065 -0.3048)
			(end 0.67945 -0.3048)
			(stroke
				(width 0.1)
				(type default)
			)
			(layer "F.Fab")
		)
		(fp_line
			(start 0.12065 -0.2794)
			(end 0.12065 -0.3048)
			(stroke
				(width 0.1)
				(type default)
			)
			(layer "F.Fab")
		)
		(fp_line
			(start 0.67945 -0.3048)
			(end 0.67945 0.3048)
			(stroke
				(width 0.1)
				(type default)
			)
			(layer "F.Fab")
		)
		(fp_line
			(start 0.67945 0.3048)
			(end 0.120396 0.3048)
			(stroke
				(width 0.1)
				(type default)
			)
			(layer "F.Fab")
		)
		(pad "1" smd circle
			(at -0.40005 0)
			(size 0 0)
			(layers "F.Cu" "F.Mask" "F.Paste")
			(net "JTAG_TRC_PCH_PTI<6>")
		)
		(pad "2" smd circle
			(at 0.40005 0)
			(size 0 0)
			(layers "F.Cu" "F.Mask" "F.Paste")
			(net "GND")
		)
	)
	(footprint ""
		(layer "F.Cu")
		(at 309.523638 -36.806886 180)
		(property "Reference" "R4102"
			(at 0 0 180)
			(layer "F.SilkS")
			(hide yes)
			(effects
				(font
					(size 1.27 1.27)
				)
			)
		)
		(property "Value" ""
			(at 0 0 180)
			(layer "F.Fab")
			(effects
				(font
					(size 1.27 1.27)
				)
			)
		)
		(duplicate_pad_numbers_are_jumpers no)
		(fp_line
			(start 0.7874 0.4064)
			(end -0.7874 0.4064)
			(stroke
				(width 0.1524)
				(type default)
			)
			(layer "F.SilkS")
		)
		(fp_line
			(start 0.7874 -0.4064)
			(end 0.7874 0.4064)
			(stroke
				(width 0.1524)
				(type default)
			)
			(layer "F.SilkS")
		)
		(fp_line
			(start -0.7874 0.4064)
			(end -0.7874 -0.4064)
			(stroke
				(width 0.1524)
				(type default)
			)
			(layer "F.SilkS")
		)
		(fp_line
			(start -0.7874 -0.4064)
			(end 0.7874 -0.4064)
			(stroke
				(width 0.1524)
				(type default)
			)
			(layer "F.SilkS")
		)
		(fp_line
			(start 0.67945 0.3048)
			(end 0.120396 0.3048)
			(stroke
				(width 0.1)
				(type default)
			)
			(layer "F.Fab")
		)
		(fp_line
			(start 0.67945 -0.3048)
			(end 0.67945 0.3048)
			(stroke
				(width 0.1)
				(type default)
			)
			(layer "F.Fab")
		)
		(fp_line
			(start 0.12065 -0.2794)
			(end 0.12065 -0.3048)
			(stroke
				(width 0.1)
				(type default)
			)
			(layer "F.Fab")
		)
		(fp_line
			(start 0.12065 -0.3048)
			(end 0.67945 -0.3048)
			(stroke
				(width 0.1)
				(type default)
			)
			(layer "F.Fab")
		)
		(fp_line
			(start 0.120396 0.3048)
			(end 0.120396 0.2794)
			(stroke
				(width 0.1)
				(type default)
			)
			(layer "F.Fab")
		)
		(fp_line
			(start 0.120396 0.2794)
			(end -0.12065 0.2794)
			(stroke
				(width 0.1)
				(type default)
			)
			(layer "F.Fab")
		)
		(fp_line
			(start -0.12065 0.3048)
			(end -0.67945 0.3048)
			(stroke
				(width 0.1)
				(type default)
			)
			(layer "F.Fab")
		)
		(fp_line
			(start -0.12065 0.2794)
			(end -0.12065 0.3048)
			(stroke
				(width 0.1)
				(type default)
			)
			(layer "F.Fab")
		)
		(fp_line
			(start -0.12065 -0.2794)
			(end 0.12065 -0.2794)
			(stroke
				(width 0.1)
				(type default)
			)
			(layer "F.Fab")
		)
		(fp_line
			(start -0.12065 -0.305054)
			(end -0.12065 -0.2794)
			(stroke
				(width 0.1)
				(type default)
			)
			(layer "F.Fab")
		)
		(fp_line
			(start -0.67945 0.3048)
			(end -0.67945 -0.305054)
			(stroke
				(width 0.1)
				(type default)
			)
			(layer "F.Fab")
		)
		(fp_line
			(start -0.67945 -0.305054)
			(end -0.12065 -0.305054)
			(stroke
				(width 0.1)
				(type default)
			)
			(layer "F.Fab")
		)
		(pad "1" smd circle
			(at -0.40005 0 180)
			(size 0 0)
			(layers "F.Cu" "F.Mask" "F.Paste")
			(net "PD_PCH_GPPC_C5")
		)
		(pad "2" smd circle
			(at 0.40005 0 180)
			(size 0 0)
			(layers "F.Cu" "F.Mask" "F.Paste")
			(net "GND")
		)
	)
	(footprint ""
		(layer "F.Cu")
		(at 483.262432 -251.033788)
		(property "Reference" "DB10"
			(at 2.310384 2.86004 90)
			(unlocked yes)
			(layer "F.SilkS")
			(effects
				(font
					(size 0.7874 0.5842)
					(thickness 0.1524)
				)
				(justify left)
			)
		)
		(property "Value" ""
			(at 0 0 0)
			(layer "F.Fab")
			(effects
				(font
					(size 1.27 1.27)
				)
			)
		)
		(duplicate_pad_numbers_are_jumpers no)
		(fp_line
			(start -3.330702 -4.771136)
			(end 3.330702 -4.771136)
			(stroke
				(width 0.1524)
				(type default)
			)
			(layer "F.SilkS")
		)
		(fp_line
			(start 0 4.011168)
			(end -3.330702 -4.771136)
			(stroke
				(width 0.1524)
				(type default)
			)
			(layer "F.SilkS")
		)
		(fp_line
			(start 3.330702 -4.771136)
			(end 0 4.011168)
			(stroke
				(width 0.1524)
				(type default)
			)
			(layer "F.SilkS")
		)
		(fp_line
			(start -3.330702 -4.771136)
			(end 3.330702 -4.771136)
			(stroke
				(width 0.1)
				(type default)
			)
			(layer "F.Fab")
		)
		(fp_line
			(start 0 4.011168)
			(end -3.330702 -4.771136)
			(stroke
				(width 0.1)
				(type default)
			)
			(layer "F.Fab")
		)
		(fp_line
			(start 3.330702 -4.771136)
			(end 0 4.011168)
			(stroke
				(width 0.1)
				(type default)
			)
			(layer "F.Fab")
		)
		(pad "1" thru_hole circle
			(at 0 0)
			(size 2.159 2.159)
			(drill 1.7018)
			(layers "*.Cu" "*.Mask")
			(remove_unused_layers no)
			(net "T1_GND")
			(clearance 0.0254)
			(thermal_gap 0.0254)
		)
		(pad "2" thru_hole circle
			(at -1.27 -3.348736)
			(size 2.159 2.159)
			(drill 1.7018)
			(layers "*.Cu" "*.Mask")
			(remove_unused_layers no)
			(net "TDR_SE_50_OHM_IN3")
			(clearance 0.0254)
			(thermal_gap 0.0254)
		)
		(pad "3" thru_hole circle
			(at 1.27 -3.348736)
			(size 2.159 2.159)
			(drill 1.7018)
			(layers "*.Cu" "*.Mask")
			(remove_unused_layers no)
			(net "TDR_SE_50_OHM_IN3")
			(clearance 0.0254)
			(thermal_gap 0.0254)
		)
	)
	(footprint ""
		(layer "F.Cu")
		(at 417.730178 -375.08053)
		(property "Reference" "PC1654"
			(at 0 0 0)
			(layer "F.SilkS")
			(hide yes)
			(effects
				(font
					(size 1.27 1.27)
				)
			)
		)
		(property "Value" ""
			(at 0 0 0)
			(layer "F.Fab")
			(effects
				(font
					(size 1.27 1.27)
				)
			)
		)
		(duplicate_pad_numbers_are_jumpers no)
		(fp_line
			(start -0.7874 -0.4064)
			(end 0.7874 -0.4064)
			(stroke
				(width 0.1524)
				(type default)
			)
			(layer "F.SilkS")
		)
		(fp_line
			(start -0.7874 0.4064)
			(end -0.7874 -0.4064)
			(stroke
				(width 0.1524)
				(type default)
			)
			(layer "F.SilkS")
		)
		(fp_line
			(start 0.7874 -0.4064)
			(end 0.7874 0.4064)
			(stroke
				(width 0.1524)
				(type default)
			)
			(layer "F.SilkS")
		)
		(fp_line
			(start 0.7874 0.4064)
			(end -0.7874 0.4064)
			(stroke
				(width 0.1524)
				(type default)
			)
			(layer "F.SilkS")
		)
		(fp_line
			(start -0.67945 -0.305054)
			(end -0.12065 -0.305054)
			(stroke
				(width 0.1)
				(type default)
			)
			(layer "F.Fab")
		)
		(fp_line
			(start -0.67945 0.3048)
			(end -0.67945 -0.305054)
			(stroke
				(width 0.1)
				(type default)
			)
			(layer "F.Fab")
		)
		(fp_line
			(start -0.12065 -0.305054)
			(end -0.12065 -0.2794)
			(stroke
				(width 0.1)
				(type default)
			)
			(layer "F.Fab")
		)
		(fp_line
			(start -0.12065 -0.2794)
			(end 0.12065 -0.2794)
			(stroke
				(width 0.1)
				(type default)
			)
			(layer "F.Fab")
		)
		(fp_line
			(start -0.12065 0.2794)
			(end -0.12065 0.3048)
			(stroke
				(width 0.1)
				(type default)
			)
			(layer "F.Fab")
		)
		(fp_line
			(start -0.12065 0.3048)
			(end -0.67945 0.3048)
			(stroke
				(width 0.1)
				(type default)
			)
			(layer "F.Fab")
		)
		(fp_line
			(start 0.120396 0.2794)
			(end -0.12065 0.2794)
			(stroke
				(width 0.1)
				(type default)
			)
			(layer "F.Fab")
		)
		(fp_line
			(start 0.120396 0.3048)
			(end 0.120396 0.2794)
			(stroke
				(width 0.1)
				(type default)
			)
			(layer "F.Fab")
		)
		(fp_line
			(start 0.12065 -0.3048)
			(end 0.67945 -0.3048)
			(stroke
				(width 0.1)
				(type default)
			)
			(layer "F.Fab")
		)
		(fp_line
			(start 0.12065 -0.2794)
			(end 0.12065 -0.3048)
			(stroke
				(width 0.1)
				(type default)
			)
			(layer "F.Fab")
		)
		(fp_line
			(start 0.67945 -0.3048)
			(end 0.67945 0.3048)
			(stroke
				(width 0.1)
				(type default)
			)
			(layer "F.Fab")
		)
		(fp_line
			(start 0.67945 0.3048)
			(end 0.120396 0.3048)
			(stroke
				(width 0.1)
				(type default)
			)
			(layer "F.Fab")
		)
		(pad "1" smd circle
			(at -0.40005 0)
			(size 0 0)
			(layers "F.Cu" "F.Mask" "F.Paste")
			(net "P12V_AUX")
		)
		(pad "2" smd circle
			(at 0.40005 0)
			(size 0 0)
			(layers "F.Cu" "F.Mask" "F.Paste")
			(net "GND")
		)
	)
	(footprint ""
		(layer "F.Cu")
		(at 61.90488 -19.268948 180)
		(property "Reference" "R3164"
			(at 0 0 180)
			(layer "F.SilkS")
			(hide yes)
			(effects
				(font
					(size 1.27 1.27)
				)
			)
		)
		(property "Value" ""
			(at 0 0 180)
			(layer "F.Fab")
			(effects
				(font
					(size 1.27 1.27)
				)
			)
		)
		(duplicate_pad_numbers_are_jumpers no)
		(fp_line
			(start 0.7874 0.4064)
			(end -0.7874 0.4064)
			(stroke
				(width 0.1524)
				(type default)
			)
			(layer "F.SilkS")
		)
		(fp_line
			(start 0.7874 -0.4064)
			(end 0.7874 0.4064)
			(stroke
				(width 0.1524)
				(type default)
			)
			(layer "F.SilkS")
		)
		(fp_line
			(start -0.7874 0.4064)
			(end -0.7874 -0.4064)
			(stroke
				(width 0.1524)
				(type default)
			)
			(layer "F.SilkS")
		)
		(fp_line
			(start -0.7874 -0.4064)
			(end 0.7874 -0.4064)
			(stroke
				(width 0.1524)
				(type default)
			)
			(layer "F.SilkS")
		)
		(fp_line
			(start 0.67945 0.3048)
			(end 0.120396 0.3048)
			(stroke
				(width 0.1)
				(type default)
			)
			(layer "F.Fab")
		)
		(fp_line
			(start 0.67945 -0.3048)
			(end 0.67945 0.3048)
			(stroke
				(width 0.1)
				(type default)
			)
			(layer "F.Fab")
		)
		(fp_line
			(start 0.12065 -0.2794)
			(end 0.12065 -0.3048)
			(stroke
				(width 0.1)
				(type default)
			)
			(layer "F.Fab")
		)
		(fp_line
			(start 0.12065 -0.3048)
			(end 0.67945 -0.3048)
			(stroke
				(width 0.1)
				(type default)
			)
			(layer "F.Fab")
		)
		(fp_line
			(start 0.120396 0.3048)
			(end 0.120396 0.2794)
			(stroke
				(width 0.1)
				(type default)
			)
			(layer "F.Fab")
		)
		(fp_line
			(start 0.120396 0.2794)
			(end -0.12065 0.2794)
			(stroke
				(width 0.1)
				(type default)
			)
			(layer "F.Fab")
		)
		(fp_line
			(start -0.12065 0.3048)
			(end -0.67945 0.3048)
			(stroke
				(width 0.1)
				(type default)
			)
			(layer "F.Fab")
		)
		(fp_line
			(start -0.12065 0.2794)
			(end -0.12065 0.3048)
			(stroke
				(width 0.1)
				(type default)
			)
			(layer "F.Fab")
		)
		(fp_line
			(start -0.12065 -0.2794)
			(end 0.12065 -0.2794)
			(stroke
				(width 0.1)
				(type default)
			)
			(layer "F.Fab")
		)
		(fp_line
			(start -0.12065 -0.305054)
			(end -0.12065 -0.2794)
			(stroke
				(width 0.1)
				(type default)
			)
			(layer "F.Fab")
		)
		(fp_line
			(start -0.67945 0.3048)
			(end -0.67945 -0.305054)
			(stroke
				(width 0.1)
				(type default)
			)
			(layer "F.Fab")
		)
		(fp_line
			(start -0.67945 -0.305054)
			(end -0.12065 -0.305054)
			(stroke
				(width 0.1)
				(type default)
			)
			(layer "F.Fab")
		)
		(pad "1" smd circle
			(at -0.40005 0 180)
			(size 0 0)
			(layers "F.Cu" "F.Mask" "F.Paste")
			(net "GND")
		)
		(pad "2" smd circle
			(at 0.40005 0 180)
			(size 0 0)
			(layers "F.Cu" "F.Mask" "F.Paste")
			(net "OCP_V3_2_AUX_PWR_EN")
		)
	)
	(footprint ""
		(layer "F.Cu")
		(at 159.655256 -63.297308)
		(property "Reference" "R2114"
			(at 0 0 0)
			(layer "F.SilkS")
			(hide yes)
			(effects
				(font
					(size 1.27 1.27)
				)
			)
		)
		(property "Value" ""
			(at 0 0 0)
			(layer "F.Fab")
			(effects
				(font
					(size 1.27 1.27)
				)
			)
		)
		(duplicate_pad_numbers_are_jumpers no)
		(fp_line
			(start -0.7874 -0.4064)
			(end 0.7874 -0.4064)
			(stroke
				(width 0.1524)
				(type default)
			)
			(layer "F.SilkS")
		)
		(fp_line
			(start -0.7874 0.4064)
			(end -0.7874 -0.4064)
			(stroke
				(width 0.1524)
				(type default)
			)
			(layer "F.SilkS")
		)
		(fp_line
			(start 0.7874 -0.4064)
			(end 0.7874 0.4064)
			(stroke
				(width 0.1524)
				(type default)
			)
			(layer "F.SilkS")
		)
		(fp_line
			(start 0.7874 0.4064)
			(end -0.7874 0.4064)
			(stroke
				(width 0.1524)
				(type default)
			)
			(layer "F.SilkS")
		)
		(fp_line
			(start -0.67945 -0.305054)
			(end -0.12065 -0.305054)
			(stroke
				(width 0.1)
				(type default)
			)
			(layer "F.Fab")
		)
		(fp_line
			(start -0.67945 0.3048)
			(end -0.67945 -0.305054)
			(stroke
				(width 0.1)
				(type default)
			)
			(layer "F.Fab")
		)
		(fp_line
			(start -0.12065 -0.305054)
			(end -0.12065 -0.2794)
			(stroke
				(width 0.1)
				(type default)
			)
			(layer "F.Fab")
		)
		(fp_line
			(start -0.12065 -0.2794)
			(end 0.12065 -0.2794)
			(stroke
				(width 0.1)
				(type default)
			)
			(layer "F.Fab")
		)
		(fp_line
			(start -0.12065 0.2794)
			(end -0.12065 0.3048)
			(stroke
				(width 0.1)
				(type default)
			)
			(layer "F.Fab")
		)
		(fp_line
			(start -0.12065 0.3048)
			(end -0.67945 0.3048)
			(stroke
				(width 0.1)
				(type default)
			)
			(layer "F.Fab")
		)
		(fp_line
			(start 0.120396 0.2794)
			(end -0.12065 0.2794)
			(stroke
				(width 0.1)
				(type default)
			)
			(layer "F.Fab")
		)
		(fp_line
			(start 0.120396 0.3048)
			(end 0.120396 0.2794)
			(stroke
				(width 0.1)
				(type default)
			)
			(layer "F.Fab")
		)
		(fp_line
			(start 0.12065 -0.3048)
			(end 0.67945 -0.3048)
			(stroke
				(width 0.1)
				(type default)
			)
			(layer "F.Fab")
		)
		(fp_line
			(start 0.12065 -0.2794)
			(end 0.12065 -0.3048)
			(stroke
				(width 0.1)
				(type default)
			)
			(layer "F.Fab")
		)
		(fp_line
			(start 0.67945 -0.3048)
			(end 0.67945 0.3048)
			(stroke
				(width 0.1)
				(type default)
			)
			(layer "F.Fab")
		)
		(fp_line
			(start 0.67945 0.3048)
			(end 0.120396 0.3048)
			(stroke
				(width 0.1)
				(type default)
			)
			(layer "F.Fab")
		)
		(pad "1" smd circle
			(at -0.40005 0)
			(size 0 0)
			(layers "F.Cu" "F.Mask" "F.Paste")
			(net "SMB_PCIE_E1S_ISO_EN_R2")
		)
		(pad "2" smd circle
			(at 0.40005 0)
			(size 0 0)
			(layers "F.Cu" "F.Mask" "F.Paste")
			(net "SMB_PCIE_E1S_ISO_EN")
		)
	)
)
